# S9S_MB_2U (Grand Teton) — schematic netlist excerpt (pin names and nets, part order shuffled) for the footprints in the layout excerpt that follows; sources: Cadence DE-HDL packaged netlist, KiCad conversion of 03242023_DA0F0TMBIJ0_F0T_Motherboard_J_brd_V01_OCP.brd

R4260  Q_RES  240 1% EMPTY  pkg 0402LF  page 119 : A = PVNN_TERM_CPU0 ; B = PD_CPU1_BIST_ENABLE
R2528  Q_RES  100K 1% CHIP  pkg 0402LF  page 247 : A = P12V_AUX ; B = FM_P12V_HSC_EN_N

(kicad_pcb
	(version 20260206)
	(generator "pcbnew")
	(generator_version "10.0")
	(general
		(thickness 1.6)
		(legacy_teardrops no)
	)
	(paper "A4")
	(title_block
		(title "03242023_DA0F0TMBIJ0_F0T_Motherboard_J_brd_V01_OCP.brd")
		(comment 1 "Grand Teton / footprints 2960-2961 of 6105")
	)
	(layers
		(0 "F.Cu" signal "TOP")
		(4 "In1.Cu" signal "GND")
		(6 "In2.Cu" signal "IN1")
		(8 "In3.Cu" signal "GND1")
		(10 "In4.Cu" signal "IN2")
		(12 "In5.Cu" signal "GND2")
		(14 "In6.Cu" signal "IN3")
		(16 "In7.Cu" signal "GND3")
		(18 "In8.Cu" signal "VCC")
		(20 "In9.Cu" signal "VCC1")
		(22 "In10.Cu" signal "GND4")
		(24 "In11.Cu" signal "IN4")
		(26 "In12.Cu" signal "GND5")
		(28 "In13.Cu" signal "IN5")
		(30 "In14.Cu" signal "GND6")
		(32 "In15.Cu" signal "IN6")
		(34 "In16.Cu" signal "GND7")
		(2 "B.Cu" signal "BOTTOM")
		(9 "F.Adhes" user "F.Adhesive")
		(11 "B.Adhes" user "B.Adhesive")
		(13 "F.Paste" user "Package Geometry/Pastemask Top")
		(15 "B.Paste" user "Package Geometry/Pastemask Bottom")
		(5 "F.SilkS" user "Ref Des/Silkscreen Top")
		(7 "B.SilkS" user "Ref Des/Silkscreen Bottom")
		(1 "F.Mask" user "Board Geometry/Soldermask Top")
		(3 "B.Mask" user "Board Geometry/Soldermask Bottom")
		(17 "Dwgs.User" user "User.Drawings")
		(19 "Cmts.User" user "User.Comments")
		(21 "Eco1.User" user "User.Eco1")
		(23 "Eco2.User" user "User.Eco2")
		(25 "Edge.Cuts" user "Board Geometry/Outline")
		(27 "Margin" user)
		(31 "F.CrtYd" user "Package Geometry/Place Bound Top")
		(29 "B.CrtYd" user "Package Geometry/Place Bound Bottom")
		(35 "F.Fab" user "Ref Des/Assembly Top")
		(33 "B.Fab" user "Ref Des/Assembly Bottom")
	)
	(footprint ""
		(layer "F.Cu")
		(at 198.9963 -131.694428 -90)
		(property "Reference" "R2528"
			(at 0 0 270)
			(layer "F.SilkS")
			(hide yes)
			(effects
				(font
					(size 1.27 1.27)
				)
			)
		)
		(property "Value" ""
			(at 0 0 270)
			(layer "F.Fab")
			(effects
				(font
					(size 1.27 1.27)
				)
			)
		)
		(duplicate_pad_numbers_are_jumpers no)
		(fp_line
			(start -0.7874 0.4064)
			(end -0.7874 -0.4064)
			(stroke
				(width 0.1524)
				(type default)
			)
			(layer "F.SilkS")
		)
		(fp_line
			(start 0.7874 0.4064)
			(end -0.7874 0.4064)
			(stroke
				(width 0.1524)
				(type default)
			)
			(layer "F.SilkS")
		)
		(fp_line
			(start -0.7874 -0.4064)
			(end 0.7874 -0.4064)
			(stroke
				(width 0.1524)
				(type default)
			)
			(layer "F.SilkS")
		)
		(fp_line
			(start 0.7874 -0.4064)
			(end 0.7874 0.4064)
			(stroke
				(width 0.1524)
				(type default)
			)
			(layer "F.SilkS")
		)
		(fp_line
			(start -0.67945 0.3048)
			(end -0.67945 -0.305054)
			(stroke
				(width 0.1)
				(type default)
			)
			(layer "F.Fab")
		)
		(fp_line
			(start -0.12065 0.3048)
			(end -0.67945 0.3048)
			(stroke
				(width 0.1)
				(type default)
			)
			(layer "F.Fab")
		)
		(fp_line
			(start 0.120396 0.3048)
			(end 0.120396 0.2794)
			(stroke
				(width 0.1)
				(type default)
			)
			(layer "F.Fab")
		)
		(fp_line
			(start 0.67945 0.3048)
			(end 0.120396 0.3048)
			(stroke
				(width 0.1)
				(type default)
			)
			(layer "F.Fab")
		)
		(fp_line
			(start -0.12065 0.2794)
			(end -0.12065 0.3048)
			(stroke
				(width 0.1)
				(type default)
			)
			(layer "F.Fab")
		)
		(fp_line
			(start 0.120396 0.2794)
			(end -0.12065 0.2794)
			(stroke
				(width 0.1)
				(type default)
			)
			(layer "F.Fab")
		)
		(fp_line
			(start -0.12065 -0.2794)
			(end 0.12065 -0.2794)
			(stroke
				(width 0.1)
				(type default)
			)
			(layer "F.Fab")
		)
		(fp_line
			(start 0.12065 -0.2794)
			(end 0.12065 -0.3048)
			(stroke
				(width 0.1)
				(type default)
			)
			(layer "F.Fab")
		)
		(fp_line
			(start 0.12065 -0.3048)
			(end 0.67945 -0.3048)
			(stroke
				(width 0.1)
				(type default)
			)
			(layer "F.Fab")
		)
		(fp_line
			(start 0.67945 -0.3048)
			(end 0.67945 0.3048)
			(stroke
				(width 0.1)
				(type default)
			)
			(layer "F.Fab")
		)
		(fp_line
			(start -0.67945 -0.305054)
			(end -0.12065 -0.305054)
			(stroke
				(width 0.1)
				(type default)
			)
			(layer "F.Fab")
		)
		(fp_line
			(start -0.12065 -0.305054)
			(end -0.12065 -0.2794)
			(stroke
				(width 0.1)
				(type default)
			)
			(layer "F.Fab")
		)
		(pad "1" smd circle
			(at -0.40005 0 270)
			(size 0 0)
			(layers "F.Cu" "F.Mask" "F.Paste")
			(net "P12V_AUX")
		)
		(pad "2" smd circle
			(at 0.40005 0 270)
			(size 0 0)
			(layers "F.Cu" "F.Mask" "F.Paste")
			(net "FM_P12V_HSC_EN_N")
		)
	)
	(footprint ""
		(layer "F.Cu")
		(at 88.442038 -179.267866 180)
		(property "Reference" "R4260"
			(at 0 0 180)
			(layer "F.SilkS")
			(hide yes)
			(effects
				(font
					(size 1.27 1.27)
				)
			)
		)
		(property "Value" ""
			(at 0 0 180)
			(layer "F.Fab")
			(effects
				(font
					(size 1.27 1.27)
				)
			)
		)
		(duplicate_pad_numbers_are_jumpers no)
		(fp_line
			(start 0.7874 0.4064)
			(end -0.7874 0.4064)
			(stroke
				(width 0.1524)
				(type default)
			)
			(layer "F.SilkS")
		)
		(fp_line
			(start 0.7874 -0.4064)
			(end 0.7874 0.4064)
			(stroke
				(width 0.1524)
				(type default)
			)
			(layer "F.SilkS")
		)
		(fp_line
			(start -0.7874 0.4064)
			(end -0.7874 -0.4064)
			(stroke
				(width 0.1524)
				(type default)
			)
			(layer "F.SilkS")
		)
		(fp_line
			(start -0.7874 -0.4064)
			(end 0.7874 -0.4064)
			(stroke
				(width 0.1524)
				(type default)
			)
			(layer "F.SilkS")
		)
		(fp_line
			(start 0.67945 0.3048)
			(end 0.120396 0.3048)
			(stroke
				(width 0.1)
				(type default)
			)
			(layer "F.Fab")
		)
		(fp_line
			(start 0.67945 -0.3048)
			(end 0.67945 0.3048)
			(stroke
				(width 0.1)
				(type default)
			)
			(layer "F.Fab")
		)
		(fp_line
			(start 0.12065 -0.2794)
			(end 0.12065 -0.3048)
			(stroke
				(width 0.1)
				(type default)
			)
			(layer "F.Fab")
		)
		(fp_line
			(start 0.12065 -0.3048)
			(end 0.67945 -0.3048)
			(stroke
				(width 0.1)
				(type default)
			)
			(layer "F.Fab")
		)
		(fp_line
			(start 0.120396 0.3048)
			(end 0.120396 0.2794)
			(stroke
				(width 0.1)
				(type default)
			)
			(layer "F.Fab")
		)
		(fp_line
			(start 0.120396 0.2794)
			(end -0.12065 0.2794)
			(stroke
				(width 0.1)
				(type default)
			)
			(layer "F.Fab")
		)
		(fp_line
			(start -0.12065 0.3048)
			(end -0.67945 0.3048)
			(stroke
				(width 0.1)
				(type default)
			)
			(layer "F.Fab")
		)
		(fp_line
			(start -0.12065 0.2794)
			(end -0.12065 0.3048)
			(stroke
				(width 0.1)
				(type default)
			)
			(layer "F.Fab")
		)
		(fp_line
			(start -0.12065 -0.2794)
			(end 0.12065 -0.2794)
			(stroke
				(width 0.1)
				(type default)
			)
			(layer "F.Fab")
		)
		(fp_line
			(start -0.12065 -0.305054)
			(end -0.12065 -0.2794)
			(stroke
				(width 0.1)
				(type default)
			)
			(layer "F.Fab")
		)
		(fp_line
			(start -0.67945 0.3048)
			(end -0.67945 -0.305054)
			(stroke
				(width 0.1)
				(type default)
			)
			(layer "F.Fab")
		)
		(fp_line
			(start -0.67945 -0.305054)
			(end -0.12065 -0.305054)
			(stroke
				(width 0.1)
				(type default)
			)
			(layer "F.Fab")
		)
		(pad "1" smd circle
			(at -0.40005 0 180)
			(size 0 0)
			(layers "F.Cu" "F.Mask" "F.Paste")
			(net "PVNN_TERM_CPU0")
		)
		(pad "2" smd circle
			(at 0.40005 0 180)
			(size 0 0)
			(layers "F.Cu" "F.Mask" "F.Paste")
			(net "PD_CPU1_BIST_ENABLE")
		)
	)
)
